# S9S_MB_2U (Grand Teton) — schematic netlist excerpt (pin names and nets, part order shuffled) for the footprints in the layout excerpt that follows; sources: Cadence DE-HDL packaged netlist, KiCad conversion of 03242023_DA0F0TMBIJ0_F0T_Motherboard_J_brd_V01_OCP.brd

R681  Q_RES  499 1% CHIP  pkg 0402LF  page 229 : A = PVNN_TERM_CPU0 ; B = I3C_SPD_DDREFGH_CPU0_SCL
C509  Q_CAP  47UF 2.5V 20% X6S  pkg C0603  page 75 : A = PVCCFA_EHV_FIVRA_CPU0 ; B = GND

(kicad_pcb
	(version 20260206)
	(generator "pcbnew")
	(generator_version "10.0")
	(general
		(thickness 1.6)
		(legacy_teardrops no)
	)
	(paper "A4")
	(title_block
		(title "03242023_DA0F0TMBIJ0_F0T_Motherboard_J_brd_V01_OCP.brd")
		(comment 1 "Grand Teton / footprints 4626-4627 of 6105")
	)
	(layers
		(0 "F.Cu" signal "TOP")
		(4 "In1.Cu" signal "GND")
		(6 "In2.Cu" signal "IN1")
		(8 "In3.Cu" signal "GND1")
		(10 "In4.Cu" signal "IN2")
		(12 "In5.Cu" signal "GND2")
		(14 "In6.Cu" signal "IN3")
		(16 "In7.Cu" signal "GND3")
		(18 "In8.Cu" signal "VCC")
		(20 "In9.Cu" signal "VCC1")
		(22 "In10.Cu" signal "GND4")
		(24 "In11.Cu" signal "IN4")
		(26 "In12.Cu" signal "GND5")
		(28 "In13.Cu" signal "IN5")
		(30 "In14.Cu" signal "GND6")
		(32 "In15.Cu" signal "IN6")
		(34 "In16.Cu" signal "GND7")
		(2 "B.Cu" signal "BOTTOM")
		(9 "F.Adhes" user "F.Adhesive")
		(11 "B.Adhes" user "B.Adhesive")
		(13 "F.Paste" user "Package Geometry/Pastemask Top")
		(15 "B.Paste" user "Package Geometry/Pastemask Bottom")
		(5 "F.SilkS" user "Ref Des/Silkscreen Top")
		(7 "B.SilkS" user "Ref Des/Silkscreen Bottom")
		(1 "F.Mask" user "Board Geometry/Soldermask Top")
		(3 "B.Mask" user "Board Geometry/Soldermask Bottom")
		(17 "Dwgs.User" user "User.Drawings")
		(19 "Cmts.User" user "User.Comments")
		(21 "Eco1.User" user "User.Eco1")
		(23 "Eco2.User" user "User.Eco2")
		(25 "Edge.Cuts" user "Board Geometry/Outline")
		(27 "Margin" user)
		(31 "F.CrtYd" user "Package Geometry/Place Bound Top")
		(29 "B.CrtYd" user "Package Geometry/Place Bound Bottom")
		(35 "F.Fab" user "Ref Des/Assembly Top")
		(33 "B.Fab" user "Ref Des/Assembly Bottom")
	)
	(footprint ""
		(layer "B.Cu")
		(at 368.203734 -237.709202 90)
		(property "Reference" "C509"
			(at 0 0 90)
			(layer "B.SilkS")
			(hide yes)
			(effects
				(font
					(size 1.27 1.27)
				)
				(justify mirror)
			)
		)
		(property "Value" ""
			(at 0 0 90)
			(layer "B.Fab")
			(effects
				(font
					(size 1.27 1.27)
				)
				(justify mirror)
			)
		)
		(duplicate_pad_numbers_are_jumpers no)
		(fp_line
			(start 1.2954 -0.5842)
			(end -1.2954 -0.5842)
			(stroke
				(width 0.1524)
				(type default)
			)
			(layer "B.SilkS")
		)
		(fp_line
			(start 0 -0.5842)
			(end 0 0.5842)
			(stroke
				(width 0.1524)
				(type default)
			)
			(layer "B.SilkS")
		)
		(fp_line
			(start -1.2954 -0.5842)
			(end -1.2954 0.5842)
			(stroke
				(width 0.1524)
				(type default)
			)
			(layer "B.SilkS")
		)
		(fp_line
			(start 1.2954 0.5842)
			(end 1.2954 -0.5842)
			(stroke
				(width 0.1524)
				(type default)
			)
			(layer "B.SilkS")
		)
		(fp_line
			(start -1.2954 0.5842)
			(end 1.2954 0.5842)
			(stroke
				(width 0.1524)
				(type default)
			)
			(layer "B.SilkS")
		)
		(fp_line
			(start 0.8636 -0.4572)
			(end -0.8636 -0.4572)
			(stroke
				(width 0.1)
				(type default)
			)
			(layer "B.Fab")
		)
		(fp_line
			(start -0.8636 -0.4572)
			(end -0.8636 -0.4064)
			(stroke
				(width 0.1)
				(type default)
			)
			(layer "B.Fab")
		)
		(fp_line
			(start 1.1938 -0.4064)
			(end 0.8636 -0.4064)
			(stroke
				(width 0.1)
				(type default)
			)
			(layer "B.Fab")
		)
		(fp_line
			(start 0.8636 -0.4064)
			(end 0.8636 -0.4572)
			(stroke
				(width 0.1)
				(type default)
			)
			(layer "B.Fab")
		)
		(fp_line
			(start -0.8636 -0.4064)
			(end -1.1938 -0.4064)
			(stroke
				(width 0.1)
				(type default)
			)
			(layer "B.Fab")
		)
		(fp_line
			(start -1.1938 -0.4064)
			(end -1.1938 0.4064)
			(stroke
				(width 0.1)
				(type default)
			)
			(layer "B.Fab")
		)
		(fp_line
			(start 1.1938 0.4064)
			(end 1.1938 -0.4064)
			(stroke
				(width 0.1)
				(type default)
			)
			(layer "B.Fab")
		)
		(fp_line
			(start 0.8636 0.4064)
			(end 1.1938 0.4064)
			(stroke
				(width 0.1)
				(type default)
			)
			(layer "B.Fab")
		)
		(fp_line
			(start -0.8636 0.4064)
			(end -0.8636 0.4572)
			(stroke
				(width 0.1)
				(type default)
			)
			(layer "B.Fab")
		)
		(fp_line
			(start -1.1938 0.4064)
			(end -0.8636 0.4064)
			(stroke
				(width 0.1)
				(type default)
			)
			(layer "B.Fab")
		)
		(fp_line
			(start 0.8636 0.4572)
			(end 0.8636 0.4064)
			(stroke
				(width 0.1)
				(type default)
			)
			(layer "B.Fab")
		)
		(fp_line
			(start -0.8636 0.4572)
			(end 0.8636 0.4572)
			(stroke
				(width 0.1)
				(type default)
			)
			(layer "B.Fab")
		)
		(pad "1" smd rect
			(at 0.7366 0)
			(size 0.7112 0.8128)
			(layers "B.Cu" "B.Mask" "B.Paste")
			(net "PVCCFA_EHV_FIVRA_CPU0")
		)
		(pad "2" smd rect
			(at -0.7366 0)
			(size 0.7112 0.8128)
			(layers "B.Cu" "B.Mask" "B.Paste")
			(net "GND")
		)
	)
	(footprint ""
		(layer "B.Cu")
		(at 377.632214 -190.703708 -90)
		(property "Reference" "R681"
			(at 0 0 90)
			(layer "B.SilkS")
			(hide yes)
			(effects
				(font
					(size 1.27 1.27)
				)
				(justify mirror)
			)
		)
		(property "Value" ""
			(at 0 0 90)
			(layer "B.Fab")
			(effects
				(font
					(size 1.27 1.27)
				)
				(justify mirror)
			)
		)
		(duplicate_pad_numbers_are_jumpers no)
		(fp_line
			(start -0.7874 0.4064)
			(end 0.7874 0.4064)
			(stroke
				(width 0.1524)
				(type default)
			)
			(layer "B.SilkS")
		)
		(fp_line
			(start 0.7874 0.4064)
			(end 0.7874 -0.4064)
			(stroke
				(width 0.1524)
				(type default)
			)
			(layer "B.SilkS")
		)
		(fp_line
			(start -0.7874 -0.4064)
			(end -0.7874 0.4064)
			(stroke
				(width 0.1524)
				(type default)
			)
			(layer "B.SilkS")
		)
		(fp_line
			(start 0.7874 -0.4064)
			(end -0.7874 -0.4064)
			(stroke
				(width 0.1524)
				(type default)
			)
			(layer "B.SilkS")
		)
		(fp_line
			(start -0.67945 0.3048)
			(end -0.120396 0.3048)
			(stroke
				(width 0.1)
				(type default)
			)
			(layer "B.Fab")
		)
		(fp_line
			(start -0.120396 0.3048)
			(end -0.120396 0.2794)
			(stroke
				(width 0.1)
				(type default)
			)
			(layer "B.Fab")
		)
		(fp_line
			(start 0.12065 0.3048)
			(end 0.67945 0.3048)
			(stroke
				(width 0.1)
				(type default)
			)
			(layer "B.Fab")
		)
		(fp_line
			(start 0.67945 0.3048)
			(end 0.67945 -0.305054)
			(stroke
				(width 0.1)
				(type default)
			)
			(layer "B.Fab")
		)
		(fp_line
			(start -0.120396 0.2794)
			(end 0.12065 0.2794)
			(stroke
				(width 0.1)
				(type default)
			)
			(layer "B.Fab")
		)
		(fp_line
			(start 0.12065 0.2794)
			(end 0.12065 0.3048)
			(stroke
				(width 0.1)
				(type default)
			)
			(layer "B.Fab")
		)
		(fp_line
			(start -0.12065 -0.2794)
			(end -0.12065 -0.3048)
			(stroke
				(width 0.1)
				(type default)
			)
			(layer "B.Fab")
		)
		(fp_line
			(start 0.12065 -0.2794)
			(end -0.12065 -0.2794)
			(stroke
				(width 0.1)
				(type default)
			)
			(layer "B.Fab")
		)
		(fp_line
			(start -0.67945 -0.3048)
			(end -0.67945 0.3048)
			(stroke
				(width 0.1)
				(type default)
			)
			(layer "B.Fab")
		)
		(fp_line
			(start -0.12065 -0.3048)
			(end -0.67945 -0.3048)
			(stroke
				(width 0.1)
				(type default)
			)
			(layer "B.Fab")
		)
		(fp_line
			(start 0.12065 -0.305054)
			(end 0.12065 -0.2794)
			(stroke
				(width 0.1)
				(type default)
			)
			(layer "B.Fab")
		)
		(fp_line
			(start 0.67945 -0.305054)
			(end 0.12065 -0.305054)
			(stroke
				(width 0.1)
				(type default)
			)
			(layer "B.Fab")
		)
		(pad "1" smd circle
			(at 0.40005 0 90)
			(size 0 0)
			(layers "B.Cu" "B.Mask" "B.Paste")
			(net "PVNN_TERM_CPU0")
		)
		(pad "2" smd circle
			(at -0.40005 0 90)
			(size 0 0)
			(layers "B.Cu" "B.Mask" "B.Paste")
			(net "I3C_SPD_DDREFGH_CPU0_SCL")
		)
	)
)
